(kicad_pcb
	(version 20260206)
	(generator "pcbnew")
	(generator_version "10.0")
	(general
		(thickness 1.6)
		(legacy_teardrops no)
	)
	(paper "A4")
	(title_block
		(title "fcb — Lightning_FCB_BRD.brd")
		(comment 1 "Lightning (Wiwynn / Facebook NVMe JBOF) / footprints 89-96 of 495")
	)
	(layers
		(0 "F.Cu" signal "TOP")
		(4 "In1.Cu" signal "L2GND")
		(6 "In2.Cu" signal "L3VCC")
		(2 "B.Cu" signal "BOTTOM")
		(9 "F.Adhes" user "F.Adhesive")
		(11 "B.Adhes" user "B.Adhesive")
		(13 "F.Paste" user "Package Geometry/Pastemask Top")
		(15 "B.Paste" user "Package Geometry/Pastemask Bottom")
		(5 "F.SilkS" user "Ref Des/Silkscreen Top")
		(7 "B.SilkS" user "Ref Des/Silkscreen Bottom")
		(1 "F.Mask" user "Board Geometry/Soldermask Top")
		(3 "B.Mask" user "Board Geometry/Soldermask Bottom")
		(17 "Dwgs.User" user "User.Drawings")
		(19 "Cmts.User" user "User.Comments")
		(21 "Eco1.User" user "User.Eco1")
		(23 "Eco2.User" user "User.Eco2")
		(25 "Edge.Cuts" user "Board Geometry/Outline")
		(27 "Margin" user)
		(31 "F.CrtYd" user "Package Geometry/Place Bound Top")
		(29 "B.CrtYd" user "Package Geometry/Place Bound Bottom")
		(35 "F.Fab" user "Ref Des/Assembly Top")
		(33 "B.Fab" user "Ref Des/Assembly Bottom")
	)
	(footprint ""
		(layer "F.Cu")
		(at 40.259 -178.054 180)
		(property "Reference" "R260"
			(at 0 0 180)
			(layer "F.SilkS")
			(hide yes)
			(effects
				(font
					(size 1.27 1.27)
				)
			)
		)
		(property "Value" "47KR2J-2-GP"
			(at 0.064008 -3.993896 180)
			(unlocked yes)
			(layer "F.Fab")
			(hide yes)
			(effects
				(font
					(size 1.016 1.016)
					(thickness 0.1524)
				)
			)
		)
		(property "Device Type" "R402H16"
			(at 0.064008 -5.517896 180)
			(unlocked yes)
			(layer "F.Fab")
			(hide yes)
			(effects
				(font
					(size 1.016 1.016)
					(thickness 0.1524)
				)
			)
		)
		(duplicate_pad_numbers_are_jumpers no)
		(fp_line
			(start 0.508 -0.9398)
			(end -0.508 -0.9398)
			(stroke
				(width 0.1524)
				(type default)
			)
			(layer "F.SilkS")
		)
		(fp_line
			(start -0.508 -0.9398)
			(end -0.508 0.9398)
			(stroke
				(width 0.1524)
				(type default)
			)
			(layer "F.SilkS")
		)
		(fp_rect
			(start -0.508 0.9398)
			(end 0.508 -0.9398)
			(stroke
				(width 0)
				(type default)
			)
			(fill no)
			(layer "F.CrtYd")
		)
		(fp_rect
			(start -0.508 0.9398)
			(end 0.508 -0.9398)
			(stroke
				(width 0)
				(type default)
			)
			(fill no)
			(layer "F.Fab")
		)
		(pad "1" smd custom
			(at 0 -0.4445 180)
			(size 0.1397 0.1397)
			(layers "F.Cu" "F.Mask" "F.Paste")
			(net "P3V3_AUX")
			(options
				(clearance outline)
				(anchor circle)
			)
			(primitives
				(gr_poly
					(pts
						(arc
							(start -0.1778 -0.2794)
							(mid -0.249642 -0.249642)
							(end -0.2794 -0.1778)
						)
						(arc
							(start -0.2794 0.1778)
							(mid -0.249642 0.249642)
							(end -0.1778 0.2794)
						)
						(arc
							(start 0.1778 0.2794)
							(mid 0.249642 0.249642)
							(end 0.2794 0.1778)
						)
						(arc
							(start 0.2794 -0.1778)
							(mid 0.249642 -0.249642)
							(end 0.1778 -0.2794)
						)
					)
					(width 0)
					(fill yes)
				)
			)
		)
		(pad "2" smd custom
			(at 0 0.4445 180)
			(size 0.1397 0.1397)
			(layers "F.Cu" "F.Mask" "F.Paste")
			(net "D_LATCH_PRE#")
			(options
				(clearance outline)
				(anchor circle)
			)
			(primitives
				(gr_poly
					(pts
						(arc
							(start -0.1778 -0.2794)
							(mid -0.249642 -0.249642)
							(end -0.2794 -0.1778)
						)
						(arc
							(start -0.2794 0.1778)
							(mid -0.249642 0.249642)
							(end -0.1778 0.2794)
						)
						(arc
							(start 0.1778 0.2794)
							(mid 0.249642 0.249642)
							(end 0.2794 0.1778)
						)
						(arc
							(start 0.2794 -0.1778)
							(mid 0.249642 -0.249642)
							(end 0.1778 -0.2794)
						)
					)
					(width 0)
					(fill yes)
				)
			)
		)
	)
	(footprint ""
		(layer "F.Cu")
		(at 17.271492 -13.919962 180)
		(property "Reference" "R69"
			(at 0 0 180)
			(layer "F.SilkS")
			(hide yes)
			(effects
				(font
					(size 1.27 1.27)
				)
			)
		)
		(property "Value" "4K7R2F-GP"
			(at 0.064008 -3.993896 180)
			(unlocked yes)
			(layer "F.Fab")
			(hide yes)
			(effects
				(font
					(size 1.016 1.016)
					(thickness 0.1524)
				)
			)
		)
		(property "Device Type" "R402H16"
			(at 0.064008 -5.517896 180)
			(unlocked yes)
			(layer "F.Fab")
			(hide yes)
			(effects
				(font
					(size 1.016 1.016)
					(thickness 0.1524)
				)
			)
		)
		(duplicate_pad_numbers_are_jumpers no)
		(fp_line
			(start 0.508 -0.9398)
			(end -0.508 -0.9398)
			(stroke
				(width 0.1524)
				(type default)
			)
			(layer "F.SilkS")
		)
		(fp_line
			(start -0.508 -0.9398)
			(end -0.508 0.9398)
			(stroke
				(width 0.1524)
				(type default)
			)
			(layer "F.SilkS")
		)
		(fp_rect
			(start -0.508 0.9398)
			(end 0.508 -0.9398)
			(stroke
				(width 0)
				(type default)
			)
			(fill no)
			(layer "F.CrtYd")
		)
		(fp_rect
			(start -0.508 0.9398)
			(end 0.508 -0.9398)
			(stroke
				(width 0)
				(type default)
			)
			(fill no)
			(layer "F.Fab")
		)
		(pad "1" smd custom
			(at 0 -0.4445 180)
			(size 0.1397 0.1397)
			(layers "F.Cu" "F.Mask" "F.Paste")
			(net "P12V")
			(options
				(clearance outline)
				(anchor circle)
			)
			(primitives
				(gr_poly
					(pts
						(arc
							(start -0.1778 -0.2794)
							(mid -0.249642 -0.249642)
							(end -0.2794 -0.1778)
						)
						(arc
							(start -0.2794 0.1778)
							(mid -0.249642 0.249642)
							(end -0.1778 0.2794)
						)
						(arc
							(start 0.1778 0.2794)
							(mid 0.249642 0.249642)
							(end 0.2794 0.1778)
						)
						(arc
							(start 0.2794 -0.1778)
							(mid 0.249642 -0.249642)
							(end 0.1778 -0.2794)
						)
					)
					(width 0)
					(fill yes)
				)
			)
		)
		(pad "2" smd custom
			(at 0 0.4445 180)
			(size 0.1397 0.1397)
			(layers "F.Cu" "F.Mask" "F.Paste")
			(net "FAN_TACH11")
			(options
				(clearance outline)
				(anchor circle)
			)
			(primitives
				(gr_poly
					(pts
						(arc
							(start -0.1778 -0.2794)
							(mid -0.249642 -0.249642)
							(end -0.2794 -0.1778)
						)
						(arc
							(start -0.2794 0.1778)
							(mid -0.249642 0.249642)
							(end -0.1778 0.2794)
						)
						(arc
							(start 0.1778 0.2794)
							(mid 0.249642 0.249642)
							(end 0.2794 0.1778)
						)
						(arc
							(start 0.2794 -0.1778)
							(mid 0.249642 -0.249642)
							(end 0.1778 -0.2794)
						)
					)
					(width 0)
					(fill yes)
				)
			)
		)
	)
	(footprint ""
		(layer "F.Cu")
		(at 33.91789 -167.723566 180)
		(property "Reference" "R11"
			(at 0 0 180)
			(layer "F.SilkS")
			(hide yes)
			(effects
				(font
					(size 1.27 1.27)
				)
			)
		)
		(property "Value" "100KR2J-1-GP"
			(at 0.064008 -3.993896 180)
			(unlocked yes)
			(layer "F.Fab")
			(hide yes)
			(effects
				(font
					(size 1.016 1.016)
					(thickness 0.1524)
				)
			)
		)
		(property "Device Type" "R402H16"
			(at 0.064008 -5.517896 180)
			(unlocked yes)
			(layer "F.Fab")
			(hide yes)
			(effects
				(font
					(size 1.016 1.016)
					(thickness 0.1524)
				)
			)
		)
		(duplicate_pad_numbers_are_jumpers no)
		(fp_line
			(start 0.508 -0.9398)
			(end -0.508 -0.9398)
			(stroke
				(width 0.1524)
				(type default)
			)
			(layer "F.SilkS")
		)
		(fp_line
			(start -0.508 -0.9398)
			(end -0.508 0.9398)
			(stroke
				(width 0.1524)
				(type default)
			)
			(layer "F.SilkS")
		)
		(fp_rect
			(start -0.508 0.9398)
			(end 0.508 -0.9398)
			(stroke
				(width 0)
				(type default)
			)
			(fill no)
			(layer "F.CrtYd")
		)
		(fp_rect
			(start -0.508 0.9398)
			(end 0.508 -0.9398)
			(stroke
				(width 0)
				(type default)
			)
			(fill no)
			(layer "F.Fab")
		)
		(pad "1" smd custom
			(at 0 -0.4445 180)
			(size 0.1397 0.1397)
			(layers "F.Cu" "F.Mask" "F.Paste")
			(net "NCT7904_ADR")
			(options
				(clearance outline)
				(anchor circle)
			)
			(primitives
				(gr_poly
					(pts
						(arc
							(start -0.1778 -0.2794)
							(mid -0.249642 -0.249642)
							(end -0.2794 -0.1778)
						)
						(arc
							(start -0.2794 0.1778)
							(mid -0.249642 0.249642)
							(end -0.1778 0.2794)
						)
						(arc
							(start 0.1778 0.2794)
							(mid 0.249642 0.249642)
							(end 0.2794 0.1778)
						)
						(arc
							(start 0.2794 -0.1778)
							(mid 0.249642 -0.249642)
							(end 0.1778 -0.2794)
						)
					)
					(width 0)
					(fill yes)
				)
			)
		)
		(pad "2" smd custom
			(at 0 0.4445 180)
			(size 0.1397 0.1397)
			(layers "F.Cu" "F.Mask" "F.Paste")
			(net "GND")
			(options
				(clearance outline)
				(anchor circle)
			)
			(primitives
				(gr_poly
					(pts
						(arc
							(start -0.1778 -0.2794)
							(mid -0.249642 -0.249642)
							(end -0.2794 -0.1778)
						)
						(arc
							(start -0.2794 0.1778)
							(mid -0.249642 0.249642)
							(end -0.1778 0.2794)
						)
						(arc
							(start 0.1778 0.2794)
							(mid 0.249642 0.249642)
							(end 0.2794 0.1778)
						)
						(arc
							(start 0.2794 -0.1778)
							(mid 0.249642 -0.249642)
							(end 0.1778 -0.2794)
						)
					)
					(width 0)
					(fill yes)
				)
			)
		)
	)
	(footprint ""
		(layer "F.Cu")
		(at 26.035 -17.399 90)
		(property "Reference" "D1"
			(at 0 0 90)
			(layer "F.SilkS")
			(hide yes)
			(effects
				(font
					(size 1.27 1.27)
				)
			)
		)
		(property "Value" "BAS16H-GP"
			(at 0 -5.5372 90)
			(unlocked yes)
			(layer "F.Fab")
			(hide yes)
			(effects
				(font
					(size 1.016 1.016)
					(thickness 0.1524)
				)
			)
		)
		(property "Device Type" "SOD123AKH48"
			(at 0 -7.0612 90)
			(unlocked yes)
			(layer "F.Fab")
			(hide yes)
			(effects
				(font
					(size 1.016 1.016)
					(thickness 0.1524)
				)
			)
		)
		(duplicate_pad_numbers_are_jumpers no)
		(fp_line
			(start 1.016 -2.667)
			(end -1.016 -2.667)
			(stroke
				(width 0.1524)
				(type default)
			)
			(layer "F.SilkS")
		)
		(fp_line
			(start -1.016 -2.667)
			(end -1.016 2.667)
			(stroke
				(width 0.1524)
				(type default)
			)
			(layer "F.SilkS")
		)
		(fp_line
			(start 1.016 2.667)
			(end 1.016 -2.667)
			(stroke
				(width 0.1524)
				(type default)
			)
			(layer "F.SilkS")
		)
		(fp_line
			(start -1.016 2.667)
			(end 1.016 2.667)
			(stroke
				(width 0.1524)
				(type default)
			)
			(layer "F.SilkS")
		)
		(fp_line
			(start 0.889 2.921)
			(end -0.889 2.921)
			(stroke
				(width 0.508)
				(type default)
			)
			(layer "F.SilkS")
		)
		(fp_rect
			(start -1.143 3.175)
			(end 1.143 -2.794)
			(stroke
				(width 0)
				(type default)
			)
			(fill no)
			(layer "F.CrtYd")
		)
		(fp_poly
			(pts
				(xy -1.143 -2.794) (xy 1.143 -2.794) (xy 1.143 3.175) (xy -1.143 3.175)
			)
			(stroke
				(width 0)
				(type default)
			)
			(fill no)
			(layer "F.Fab")
		)
		(pad "A" smd rect
			(at 0 -1.6891 90)
			(size 0.889 1.397)
			(layers "F.Cu" "F.Mask" "F.Paste")
			(net "FAN_TACH12")
		)
		(pad "K" smd rect
			(at 0 1.6891 90)
			(size 0.889 1.397)
			(layers "F.Cu" "F.Mask" "F.Paste")
			(net "P12V")
		)
	)
	(footprint ""
		(layer "F.Cu")
		(at 13.6652 -256.8702)
		(property "Reference" "C38"
			(at 0 0 0)
			(layer "F.SilkS")
			(hide yes)
			(effects
				(font
					(size 1.27 1.27)
				)
			)
		)
		(property "Value" "SCD1U16V2KX-3GP"
			(at 1.1811 -2.7051 0)
			(unlocked yes)
			(layer "F.Fab")
			(hide yes)
			(effects
				(font
					(size 1.016 1.016)
					(thickness 0.1524)
				)
			)
		)
		(property "Device Type" "C402H22"
			(at 1.1811 -4.2291 0)
			(unlocked yes)
			(layer "F.Fab")
			(hide yes)
			(effects
				(font
					(size 1.016 1.016)
					(thickness 0.1524)
				)
			)
		)
		(duplicate_pad_numbers_are_jumpers no)
		(fp_rect
			(start -0.4318 0.9525)
			(end 0.4318 -0.9525)
			(stroke
				(width 0)
				(type default)
			)
			(fill no)
			(layer "F.CrtYd")
		)
		(fp_rect
			(start -0.4318 0.9525)
			(end 0.4318 -0.9525)
			(stroke
				(width 0)
				(type default)
			)
			(fill no)
			(layer "F.Fab")
		)
		(pad "1" smd custom
			(at 0 -0.4445)
			(size 0.1524 0.1524)
			(layers "F.Cu" "F.Mask" "F.Paste")
			(net "FAN_TACH5")
			(options
				(clearance outline)
				(anchor circle)
			)
			(primitives
				(gr_poly
					(pts
						(arc
							(start 0.3048 -0.2032)
							(mid 0.275042 -0.275042)
							(end 0.2032 -0.3048)
						)
						(arc
							(start -0.2032 -0.3048)
							(mid -0.275042 -0.275042)
							(end -0.3048 -0.2032)
						)
						(arc
							(start -0.3048 0.2032)
							(mid -0.275042 0.275042)
							(end -0.2032 0.3048)
						)
						(arc
							(start 0.2032 0.3048)
							(mid 0.275042 0.275042)
							(end 0.3048 0.2032)
						)
					)
					(width 0)
					(fill yes)
				)
			)
		)
		(pad "2" smd custom
			(at 0 0.4445)
			(size 0.1524 0.1524)
			(layers "F.Cu" "F.Mask" "F.Paste")
			(net "GND")
			(options
				(clearance outline)
				(anchor circle)
			)
			(primitives
				(gr_poly
					(pts
						(arc
							(start 0.3048 -0.2032)
							(mid 0.275042 -0.275042)
							(end 0.2032 -0.3048)
						)
						(arc
							(start -0.2032 -0.3048)
							(mid -0.275042 -0.275042)
							(end -0.3048 -0.2032)
						)
						(arc
							(start -0.3048 0.2032)
							(mid -0.275042 0.275042)
							(end -0.2032 0.3048)
						)
						(arc
							(start 0.2032 0.3048)
							(mid 0.275042 0.275042)
							(end 0.3048 0.2032)
						)
					)
					(width 0)
					(fill yes)
				)
			)
		)
	)
	(footprint ""
		(layer "F.Cu")
		(at 14.8844 -43.5102 -90)
		(property "Reference" "R118"
			(at 0 0 270)
			(layer "F.SilkS")
			(hide yes)
			(effects
				(font
					(size 1.27 1.27)
				)
			)
		)
		(property "Value" "470R2F-GP"
			(at 0.064008 -3.993896 270)
			(unlocked yes)
			(layer "F.Fab")
			(hide yes)
			(effects
				(font
					(size 1.016 1.016)
					(thickness 0.1524)
				)
			)
		)
		(property "Device Type" "R402H16"
			(at 0.064008 -5.517896 270)
			(unlocked yes)
			(layer "F.Fab")
			(hide yes)
			(effects
				(font
					(size 1.016 1.016)
					(thickness 0.1524)
				)
			)
		)
		(duplicate_pad_numbers_are_jumpers no)
		(fp_line
			(start -0.508 -0.9398)
			(end -0.508 0.9398)
			(stroke
				(width 0.1524)
				(type default)
			)
			(layer "F.SilkS")
		)
		(fp_line
			(start 0.508 -0.9398)
			(end -0.508 -0.9398)
			(stroke
				(width 0.1524)
				(type default)
			)
			(layer "F.SilkS")
		)
		(fp_rect
			(start -0.508 0.9398)
			(end 0.508 -0.9398)
			(stroke
				(width 0)
				(type default)
			)
			(fill no)
			(layer "F.CrtYd")
		)
		(fp_rect
			(start -0.508 0.9398)
			(end 0.508 -0.9398)
			(stroke
				(width 0)
				(type default)
			)
			(fill no)
			(layer "F.Fab")
		)
		(pad "1" smd custom
			(at 0 -0.4445 270)
			(size 0.1397 0.1397)
			(layers "F.Cu" "F.Mask" "F.Paste")
			(net "SEB_PEER_2A_HB")
			(options
				(clearance outline)
				(anchor circle)
			)
			(primitives
				(gr_poly
					(pts
						(arc
							(start -0.1778 -0.2794)
							(mid -0.249642 -0.249642)
							(end -0.2794 -0.1778)
						)
						(arc
							(start -0.2794 0.1778)
							(mid -0.249642 0.249642)
							(end -0.1778 0.2794)
						)
						(arc
							(start 0.1778 0.2794)
							(mid 0.249642 0.249642)
							(end 0.2794 0.1778)
						)
						(arc
							(start 0.2794 -0.1778)
							(mid 0.249642 -0.249642)
							(end 0.1778 -0.2794)
						)
					)
					(width 0)
					(fill yes)
				)
			)
		)
		(pad "2" smd custom
			(at 0 0.4445 270)
			(size 0.1397 0.1397)
			(layers "F.Cu" "F.Mask" "F.Paste")
			(net "GND")
			(options
				(clearance outline)
				(anchor circle)
			)
			(primitives
				(gr_poly
					(pts
						(arc
							(start -0.1778 -0.2794)
							(mid -0.249642 -0.249642)
							(end -0.2794 -0.1778)
						)
						(arc
							(start -0.2794 0.1778)
							(mid -0.249642 0.249642)
							(end -0.1778 0.2794)
						)
						(arc
							(start 0.1778 0.2794)
							(mid 0.249642 0.249642)
							(end 0.2794 0.1778)
						)
						(arc
							(start 0.2794 -0.1778)
							(mid 0.249642 -0.249642)
							(end 0.1778 -0.2794)
						)
					)
					(width 0)
					(fill yes)
				)
			)
		)
	)
	(footprint ""
		(layer "F.Cu")
		(at 9.3218 -454.2028 -90)
		(property "Reference" "R96"
			(at 0 0 270)
			(layer "F.SilkS")
			(hide yes)
			(effects
				(font
					(size 1.27 1.27)
				)
			)
		)
		(property "Value" "4K7R2F-GP"
			(at 0.064008 -3.993896 270)
			(unlocked yes)
			(layer "F.Fab")
			(hide yes)
			(effects
				(font
					(size 1.016 1.016)
					(thickness 0.1524)
				)
			)
		)
		(property "Device Type" "R402H16"
			(at 0.064008 -5.517896 270)
			(unlocked yes)
			(layer "F.Fab")
			(hide yes)
			(effects
				(font
					(size 1.016 1.016)
					(thickness 0.1524)
				)
			)
		)
		(duplicate_pad_numbers_are_jumpers no)
		(fp_line
			(start -0.508 -0.9398)
			(end -0.508 0.9398)
			(stroke
				(width 0.1524)
				(type default)
			)
			(layer "F.SilkS")
		)
		(fp_line
			(start 0.508 -0.9398)
			(end -0.508 -0.9398)
			(stroke
				(width 0.1524)
				(type default)
			)
			(layer "F.SilkS")
		)
		(fp_rect
			(start -0.508 0.9398)
			(end 0.508 -0.9398)
			(stroke
				(width 0)
				(type default)
			)
			(fill no)
			(layer "F.CrtYd")
		)
		(fp_rect
			(start -0.508 0.9398)
			(end 0.508 -0.9398)
			(stroke
				(width 0)
				(type default)
			)
			(fill no)
			(layer "F.Fab")
		)
		(pad "1" smd custom
			(at 0 -0.4445 270)
			(size 0.1397 0.1397)
			(layers "F.Cu" "F.Mask" "F.Paste")
			(net "P12V")
			(options
				(clearance outline)
				(anchor circle)
			)
			(primitives
				(gr_poly
					(pts
						(arc
							(start -0.1778 -0.2794)
							(mid -0.249642 -0.249642)
							(end -0.2794 -0.1778)
						)
						(arc
							(start -0.2794 0.1778)
							(mid -0.249642 0.249642)
							(end -0.1778 0.2794)
						)
						(arc
							(start 0.1778 0.2794)
							(mid 0.249642 0.249642)
							(end 0.2794 0.1778)
						)
						(arc
							(start 0.2794 -0.1778)
							(mid 0.249642 -0.249642)
							(end 0.1778 -0.2794)
						)
					)
					(width 0)
					(fill yes)
				)
			)
		)
		(pad "2" smd custom
			(at 0 0.4445 270)
			(size 0.1397 0.1397)
			(layers "F.Cu" "F.Mask" "F.Paste")
			(net "PWM_OUT_FAN1_NET")
			(options
				(clearance outline)
				(anchor circle)
			)
			(primitives
				(gr_poly
					(pts
						(arc
							(start -0.1778 -0.2794)
							(mid -0.249642 -0.249642)
							(end -0.2794 -0.1778)
						)
						(arc
							(start -0.2794 0.1778)
							(mid -0.249642 0.249642)
							(end -0.1778 0.2794)
						)
						(arc
							(start 0.1778 0.2794)
							(mid 0.249642 0.249642)
							(end 0.2794 0.1778)
						)
						(arc
							(start 0.2794 -0.1778)
							(mid 0.249642 -0.249642)
							(end 0.1778 -0.2794)
						)
					)
					(width 0)
					(fill yes)
				)
			)
		)
	)
	(footprint ""
		(layer "F.Cu")
		(at 22.225 -222.416116 180)
		(property "Reference" "C16"
			(at 0 0 180)
			(layer "F.SilkS")
			(hide yes)
			(effects
				(font
					(size 1.27 1.27)
				)
			)
		)
		(property "Value" "SCD1U50V3KX-GP"
			(at 0 -2.8194 180)
			(unlocked yes)
			(layer "F.Fab")
			(hide yes)
			(effects
				(font
					(size 1.016 1.016)
					(thickness 0.1524)
				)
			)
		)
		(property "Device Type" "C603H36"
			(at 0 -4.3434 180)
			(unlocked yes)
			(layer "F.Fab")
			(hide yes)
			(effects
				(font
					(size 1.016 1.016)
					(thickness 0.1524)
				)
			)
		)
		(duplicate_pad_numbers_are_jumpers no)
		(fp_line
			(start 0.508 0)
			(end -0.508 0)
			(stroke
				(width 0.2032)
				(type default)
			)
			(layer "F.SilkS")
		)
		(fp_rect
			(start -0.5842 1.3335)
			(end 0.5842 -1.3335)
			(stroke
				(width 0)
				(type default)
			)
			(fill no)
			(layer "F.CrtYd")
		)
		(fp_rect
			(start -0.5842 1.3335)
			(end 0.5842 -1.3335)
			(stroke
				(width 0)
				(type default)
			)
			(fill no)
			(layer "F.Fab")
		)
		(pad "1" smd custom
			(at 0 -0.762 180)
			(size 0.2159 0.2159)
			(layers "F.Cu" "F.Mask" "F.Paste")
			(net "P3V3")
			(options
				(clearance outline)
				(anchor circle)
			)
			(primitives
				(gr_poly
					(pts
						(arc
							(start -0.3302 -0.4318)
							(mid -0.402042 -0.402042)
							(end -0.4318 -0.3302)
						)
						(arc
							(start -0.4318 0.3302)
							(mid -0.402042 0.402042)
							(end -0.3302 0.4318)
						)
						(arc
							(start 0.3302 0.4318)
							(mid 0.402042 0.402042)
							(end 0.4318 0.3302)
						)
						(arc
							(start 0.4318 -0.3302)
							(mid 0.402042 -0.402042)
							(end 0.3302 -0.4318)
						)
					)
					(width 0)
					(fill yes)
				)
			)
		)
		(pad "2" smd custom
			(at 0 0.762 180)
			(size 0.2159 0.2159)
			(layers "F.Cu" "F.Mask" "F.Paste")
			(net "GND")
			(options
				(clearance outline)
				(anchor circle)
			)
			(primitives
				(gr_poly
					(pts
						(arc
							(start -0.3302 -0.4318)
							(mid -0.402042 -0.402042)
							(end -0.4318 -0.3302)
						)
						(arc
							(start -0.4318 0.3302)
							(mid -0.402042 0.402042)
							(end -0.3302 0.4318)
						)
						(arc
							(start 0.3302 0.4318)
							(mid 0.402042 0.402042)
							(end 0.4318 0.3302)
						)
						(arc
							(start 0.4318 -0.3302)
							(mid 0.402042 -0.402042)
							(end 0.3302 -0.4318)
						)
					)
					(width 0)
					(fill yes)
				)
			)
		)
	)
)
